(kicad_pcb
	(version 20260206)
	(generator "pcbnew")
	(generator_version "10.0")
	(general
		(thickness 1.6)
		(legacy_teardrops no)
	)
	(paper "A4")
	(title_block
		(title "v1-chassis-manager — T6M_CM_d_v01_1031_1645.brd")
		(comment 1 "Open CloudServer (Microsoft) / footprints 1233-1241 of 2512")
	)
	(layers
		(0 "F.Cu" signal "TOP")
		(4 "In1.Cu" signal "GND1")
		(6 "In2.Cu" signal "IN1")
		(8 "In3.Cu" signal "VCC1")
		(10 "In4.Cu" signal "VCC2")
		(12 "In5.Cu" signal "GND2")
		(14 "In6.Cu" signal "IN2")
		(16 "In7.Cu" signal "IN3")
		(18 "In8.Cu" signal "GND3")
		(2 "B.Cu" signal "BOTTOM")
		(9 "F.Adhes" user "F.Adhesive")
		(11 "B.Adhes" user "B.Adhesive")
		(13 "F.Paste" user "Package Geometry/Pastemask Top")
		(15 "B.Paste" user "Package Geometry/Pastemask Bottom")
		(5 "F.SilkS" user "Ref Des/Silkscreen Top")
		(7 "B.SilkS" user "Ref Des/Silkscreen Bottom")
		(1 "F.Mask" user "Board Geometry/Soldermask Top")
		(3 "B.Mask" user "Board Geometry/Soldermask Bottom")
		(17 "Dwgs.User" user "User.Drawings")
		(19 "Cmts.User" user "User.Comments")
		(21 "Eco1.User" user "User.Eco1")
		(23 "Eco2.User" user "User.Eco2")
		(25 "Edge.Cuts" user "Board Geometry/Outline")
		(27 "Margin" user)
		(31 "F.CrtYd" user "Package Geometry/Place Bound Top")
		(29 "B.CrtYd" user "Package Geometry/Place Bound Bottom")
		(35 "F.Fab" user "Ref Des/Assembly Top")
		(33 "B.Fab" user "Ref Des/Assembly Bottom")
	)
	(footprint ""
		(layer "F.Cu")
		(at 121.516394 -151.266906 -90)
		(property "Reference" "R1250"
			(at 1.75641 -2.386584 90)
			(unlocked yes)
			(layer "F.SilkS")
			(effects
				(font
					(size 0.635 0.4064)
					(thickness 0.1524)
				)
				(justify left)
			)
		)
		(property "Value" ""
			(at 0 0 270)
			(layer "F.Fab")
			(effects
				(font
					(size 1.27 1.27)
				)
			)
		)
		(duplicate_pad_numbers_are_jumpers no)
		(fp_line
			(start -0.7874 0.4064)
			(end -0.7874 -0.4064)
			(stroke
				(width 0.1524)
				(type default)
			)
			(layer "F.SilkS")
		)
		(fp_line
			(start 0.7874 0.4064)
			(end -0.7874 0.4064)
			(stroke
				(width 0.1524)
				(type default)
			)
			(layer "F.SilkS")
		)
		(fp_line
			(start -0.7874 -0.4064)
			(end 0.7874 -0.4064)
			(stroke
				(width 0.1524)
				(type default)
			)
			(layer "F.SilkS")
		)
		(fp_line
			(start 0.7874 -0.4064)
			(end 0.7874 0.4064)
			(stroke
				(width 0.1524)
				(type default)
			)
			(layer "F.SilkS")
		)
		(fp_poly
			(pts
				(xy -0.508 0.2794) (xy -0.508 0.2286) (xy -0.635 0.2286) (xy -0.635 -0.254) (xy -0.5334 -0.254)
				(xy -0.5334 -0.2794) (xy 0.5334 -0.2794) (xy 0.5334 -0.254) (xy 0.635 -0.254) (xy 0.635 0.254) (xy 0.5334 0.254)
				(xy 0.5334 0.2794)
			)
			(stroke
				(width 0)
				(type default)
			)
			(fill no)
			(layer "F.CrtYd")
		)
		(pad "1" smd rect
			(at 0.40005 0 270)
			(size 0.4572 0.508)
			(layers "F.Cu" "F.Mask" "F.Paste")
			(net "N52998345")
		)
		(pad "2" smd rect
			(at -0.40005 0 270)
			(size 0.4572 0.508)
			(layers "F.Cu" "F.Mask" "F.Paste")
			(net "N52998343")
		)
	)
	(footprint ""
		(layer "F.Cu")
		(at 131.30276 -188.126624 -90)
		(property "Reference" "R992"
			(at -4.949444 0.837438 90)
			(unlocked yes)
			(layer "F.SilkS")
			(effects
				(font
					(size 0.7874 0.5842)
					(thickness 0.1524)
				)
				(justify left)
			)
		)
		(property "Value" ""
			(at 0 0 270)
			(layer "F.Fab")
			(effects
				(font
					(size 1.27 1.27)
				)
			)
		)
		(duplicate_pad_numbers_are_jumpers no)
		(fp_line
			(start -0.7874 0.4064)
			(end -0.7874 -0.4064)
			(stroke
				(width 0.1524)
				(type default)
			)
			(layer "F.SilkS")
		)
		(fp_line
			(start 0.7874 0.4064)
			(end -0.7874 0.4064)
			(stroke
				(width 0.1524)
				(type default)
			)
			(layer "F.SilkS")
		)
		(fp_line
			(start -0.7874 -0.4064)
			(end 0.7874 -0.4064)
			(stroke
				(width 0.1524)
				(type default)
			)
			(layer "F.SilkS")
		)
		(fp_line
			(start 0.7874 -0.4064)
			(end 0.7874 0.4064)
			(stroke
				(width 0.1524)
				(type default)
			)
			(layer "F.SilkS")
		)
		(fp_poly
			(pts
				(xy -0.508 0.2794) (xy -0.508 0.2286) (xy -0.635 0.2286) (xy -0.635 -0.254) (xy -0.5334 -0.254)
				(xy -0.5334 -0.2794) (xy 0.5334 -0.2794) (xy 0.5334 -0.254) (xy 0.635 -0.254) (xy 0.635 0.254) (xy 0.5334 0.254)
				(xy 0.5334 0.2794)
			)
			(stroke
				(width 0)
				(type default)
			)
			(fill no)
			(layer "F.CrtYd")
		)
		(pad "1" smd rect
			(at 0.40005 0 270)
			(size 0.4572 0.508)
			(layers "F.Cu" "F.Mask" "F.Paste")
			(net "UART_T10_NODE3_RXD")
		)
		(pad "2" smd rect
			(at -0.40005 0 270)
			(size 0.4572 0.508)
			(layers "F.Cu" "F.Mask" "F.Paste")
			(net "UART_T10_NODE3_RXD_R")
		)
	)
	(footprint ""
		(layer "F.Cu")
		(at 67.67576 -185.205624 -90)
		(property "Reference" "R874"
			(at -4.006088 0.786892 90)
			(unlocked yes)
			(layer "F.SilkS")
			(effects
				(font
					(size 0.7874 0.5842)
					(thickness 0.1524)
				)
				(justify left)
			)
		)
		(property "Value" ""
			(at 0 0 270)
			(layer "F.Fab")
			(effects
				(font
					(size 1.27 1.27)
				)
			)
		)
		(duplicate_pad_numbers_are_jumpers no)
		(fp_line
			(start -0.7874 0.4064)
			(end -0.7874 -0.4064)
			(stroke
				(width 0.1524)
				(type default)
			)
			(layer "F.SilkS")
		)
		(fp_line
			(start 0.7874 0.4064)
			(end -0.7874 0.4064)
			(stroke
				(width 0.1524)
				(type default)
			)
			(layer "F.SilkS")
		)
		(fp_line
			(start -0.7874 -0.4064)
			(end 0.7874 -0.4064)
			(stroke
				(width 0.1524)
				(type default)
			)
			(layer "F.SilkS")
		)
		(fp_line
			(start 0.7874 -0.4064)
			(end 0.7874 0.4064)
			(stroke
				(width 0.1524)
				(type default)
			)
			(layer "F.SilkS")
		)
		(fp_poly
			(pts
				(xy -0.508 0.2794) (xy -0.508 0.2286) (xy -0.635 0.2286) (xy -0.635 -0.254) (xy -0.5334 -0.254)
				(xy -0.5334 -0.2794) (xy 0.5334 -0.2794) (xy 0.5334 -0.254) (xy 0.635 -0.254) (xy 0.635 0.254) (xy 0.5334 0.254)
				(xy 0.5334 0.2794)
			)
			(stroke
				(width 0)
				(type default)
			)
			(fill no)
			(layer "F.CrtYd")
		)
		(pad "1" smd rect
			(at 0.40005 0 270)
			(size 0.4572 0.508)
			(layers "F.Cu" "F.Mask" "F.Paste")
			(net "T2_NODE2_EN")
		)
		(pad "2" smd rect
			(at -0.40005 0 270)
			(size 0.4572 0.508)
			(layers "F.Cu" "F.Mask" "F.Paste")
			(net "T2_NODE2_EN_R")
		)
	)
	(footprint ""
		(layer "F.Cu")
		(at 137.076688 -66.893948)
		(property "Reference" "Q12"
			(at -1.456436 -2.032254 0)
			(unlocked yes)
			(layer "F.SilkS")
			(effects
				(font
					(size 0.7874 0.5842)
					(thickness 0.1524)
				)
			)
		)
		(property "Value" ""
			(at 0 0 0)
			(layer "F.Fab")
			(effects
				(font
					(size 1.27 1.27)
				)
			)
		)
		(duplicate_pad_numbers_are_jumpers no)
		(fp_line
			(start -1.488186 -1.500124)
			(end 1.488186 -1.500124)
			(stroke
				(width 0.1524)
				(type default)
			)
			(layer "F.SilkS")
		)
		(fp_line
			(start -1.488186 1.500124)
			(end -1.488186 -1.500124)
			(stroke
				(width 0.1524)
				(type default)
			)
			(layer "F.SilkS")
		)
		(fp_line
			(start 1.488186 -1.500124)
			(end 1.488186 1.500124)
			(stroke
				(width 0.1524)
				(type default)
			)
			(layer "F.SilkS")
		)
		(fp_line
			(start 1.488186 1.500124)
			(end -1.488186 1.500124)
			(stroke
				(width 0.1524)
				(type default)
			)
			(layer "F.SilkS")
		)
		(fp_poly
			(pts
				(xy -0.700024 1.500124) (xy 0.700024 1.500124) (xy 0.700024 0.3556) (xy 1.4224 0.3556) (xy 1.4224 -0.3556)
				(xy 0.700024 -0.3556) (xy 0.700024 -1.500124) (xy -0.700024 -1.500124) (xy -0.700024 -1.3208) (xy -1.4224 -1.3208)
				(xy -1.4224 -0.5842) (xy -0.700024 -0.5842) (xy -0.700024 0.5842) (xy -1.4224 0.5842) (xy -1.4224 1.3208)
				(xy -0.700024 1.3208)
			)
			(stroke
				(width 0)
				(type default)
			)
			(fill no)
			(layer "F.CrtYd")
		)
		(fp_line
			(start -0.700024 -1.500124)
			(end 0.700024 -1.500124)
			(stroke
				(width 0.1)
				(type default)
			)
			(layer "F.Fab")
		)
		(fp_line
			(start -0.700024 1.500124)
			(end -0.700024 -1.500124)
			(stroke
				(width 0.1)
				(type default)
			)
			(layer "F.Fab")
		)
		(fp_line
			(start 0.700024 -1.500124)
			(end 0.700024 1.500124)
			(stroke
				(width 0.1)
				(type default)
			)
			(layer "F.Fab")
		)
		(fp_line
			(start 0.700024 1.500124)
			(end -0.700024 1.500124)
			(stroke
				(width 0.1)
				(type default)
			)
			(layer "F.Fab")
		)
		(fp_text user "1"
			(at -1.784604 -0.378714 0)
			(unlocked yes)
			(layer "F.SilkS")
			(effects
				(font
					(size 0.7874 0.5842)
					(thickness 0.1524)
				)
			)
		)
		(fp_text user "2"
			(at 1.745234 1.965706 90)
			(unlocked yes)
			(layer "F.SilkS")
			(effects
				(font
					(size 0.7874 0.5842)
					(thickness 0.1524)
				)
			)
		)
		(fp_text user "3"
			(at 1.972564 0.468376 0)
			(unlocked yes)
			(layer "F.SilkS")
			(effects
				(font
					(size 0.7874 0.5842)
					(thickness 0.1524)
				)
			)
		)
		(fp_text user "1"
			(at -0.90805 -1.8034 270)
			(unlocked yes)
			(layer "F.Fab")
			(effects
				(font
					(size 0.7874 0.5842)
					(thickness 0.000001)
				)
			)
		)
		(fp_text user "2"
			(at -0.90805 1.8542 270)
			(unlocked yes)
			(layer "F.Fab")
			(effects
				(font
					(size 0.7874 0.5842)
					(thickness 0.000001)
				)
			)
		)
		(fp_text user "3"
			(at 2.15773 0 270)
			(unlocked yes)
			(layer "F.Fab")
			(effects
				(font
					(size 0.7874 0.5842)
					(thickness 0.000001)
				)
			)
		)
		(pad "1" smd rect
			(at -0.999998 -0.94996 270)
			(size 0.6096 0.7112)
			(layers "F.Cu" "F.Mask" "F.Paste")
			(net "SATA_VCONT_NODE1")
		)
		(pad "2" smd rect
			(at -0.999998 0.94996 270)
			(size 0.6096 0.7112)
			(layers "F.Cu" "F.Mask" "F.Paste")
			(net "P1V8_NODE1")
		)
		(pad "3" smd rect
			(at 0.999998 0 270)
			(size 0.6096 0.7112)
			(layers "F.Cu" "F.Mask" "F.Paste")
			(net "P1V0_SATA")
		)
	)
	(footprint ""
		(layer "F.Cu")
		(at 53.017166 -96.709992 90)
		(property "Reference" "R84"
			(at -54.98719 28.429712 90)
			(unlocked yes)
			(layer "F.SilkS")
			(effects
				(font
					(size 0.7874 0.5842)
					(thickness 0.1524)
				)
				(justify left)
			)
		)
		(property "Value" ""
			(at 0 0 90)
			(layer "F.Fab")
			(effects
				(font
					(size 1.27 1.27)
				)
			)
		)
		(duplicate_pad_numbers_are_jumpers no)
		(fp_line
			(start 0.7874 -0.4064)
			(end 0.7874 0.4064)
			(stroke
				(width 0.1524)
				(type default)
			)
			(layer "F.SilkS")
		)
		(fp_line
			(start -0.7874 -0.4064)
			(end 0.7874 -0.4064)
			(stroke
				(width 0.1524)
				(type default)
			)
			(layer "F.SilkS")
		)
		(fp_line
			(start 0.7874 0.4064)
			(end -0.7874 0.4064)
			(stroke
				(width 0.1524)
				(type default)
			)
			(layer "F.SilkS")
		)
		(fp_line
			(start -0.7874 0.4064)
			(end -0.7874 -0.4064)
			(stroke
				(width 0.1524)
				(type default)
			)
			(layer "F.SilkS")
		)
		(fp_poly
			(pts
				(xy -0.508 0.2794) (xy -0.508 0.2286) (xy -0.635 0.2286) (xy -0.635 -0.254) (xy -0.5334 -0.254)
				(xy -0.5334 -0.2794) (xy 0.5334 -0.2794) (xy 0.5334 -0.254) (xy 0.635 -0.254) (xy 0.635 0.254) (xy 0.5334 0.254)
				(xy 0.5334 0.2794)
			)
			(stroke
				(width 0)
				(type default)
			)
			(fill no)
			(layer "F.CrtYd")
		)
		(pad "1" smd rect
			(at 0.40005 0 90)
			(size 0.4572 0.508)
			(layers "F.Cu" "F.Mask" "F.Paste")
			(net "GND")
		)
		(pad "2" smd rect
			(at -0.40005 0 90)
			(size 0.4572 0.508)
			(layers "F.Cu" "F.Mask" "F.Paste")
			(net "PD_CPU_NODE1_DFX_GPIO_GRP0_1")
		)
	)
	(footprint ""
		(layer "F.Cu")
		(at 30.549088 -132.850382 180)
		(property "Reference" "C833"
			(at 1.261872 3.138424 0)
			(unlocked yes)
			(layer "F.SilkS")
			(effects
				(font
					(size 0.7874 0.5842)
					(thickness 0.1524)
				)
				(justify left)
			)
		)
		(property "Value" ""
			(at 0 0 180)
			(layer "F.Fab")
			(effects
				(font
					(size 1.27 1.27)
				)
			)
		)
		(duplicate_pad_numbers_are_jumpers no)
		(fp_line
			(start 0.7874 0.4064)
			(end -0.7874 0.4064)
			(stroke
				(width 0.1524)
				(type default)
			)
			(layer "F.SilkS")
		)
		(fp_line
			(start 0.7874 -0.4064)
			(end 0.7874 0.4064)
			(stroke
				(width 0.1524)
				(type default)
			)
			(layer "F.SilkS")
		)
		(fp_line
			(start 0 0.381)
			(end 0 -0.381)
			(stroke
				(width 0.1524)
				(type default)
			)
			(layer "F.SilkS")
		)
		(fp_line
			(start -0.7874 0.4064)
			(end -0.7874 -0.4064)
			(stroke
				(width 0.1524)
				(type default)
			)
			(layer "F.SilkS")
		)
		(fp_line
			(start -0.7874 -0.4064)
			(end 0.7874 -0.4064)
			(stroke
				(width 0.1524)
				(type default)
			)
			(layer "F.SilkS")
		)
		(fp_poly
			(pts
				(xy -0.5334 0.254) (xy -0.635 0.254) (xy -0.635 0.2286) (xy -0.635 -0.254) (xy -0.5334 -0.254) (xy -0.5334 -0.2794)
				(xy 0.5334 -0.2794) (xy 0.5334 -0.254) (xy 0.635 -0.254) (xy 0.635 0.254) (xy 0.5334 0.254) (xy 0.5334 0.2794)
				(xy -0.508 0.2794) (xy -0.5334 0.2794)
			)
			(stroke
				(width 0)
				(type default)
			)
			(fill no)
			(layer "F.CrtYd")
		)
		(pad "1" smd rect
			(at 0.40005 0 180)
			(size 0.4572 0.508)
			(layers "F.Cu" "F.Mask" "F.Paste")
			(net "P1V538_BMC_NODE1_ADJ")
		)
		(pad "2" smd rect
			(at -0.40005 0 180)
			(size 0.4572 0.508)
			(layers "F.Cu" "F.Mask" "F.Paste")
			(net "P1V538_STB_NODE1_ADJ_S")
		)
	)
	(footprint ""
		(layer "F.Cu")
		(at 161.489898 -72.400668)
		(property "Reference" "R1218"
			(at -6.716776 -1.069594 0)
			(unlocked yes)
			(layer "F.SilkS")
			(effects
				(font
					(size 0.7874 0.5842)
					(thickness 0.1524)
				)
				(justify left)
			)
		)
		(property "Value" ""
			(at 0 0 0)
			(layer "F.Fab")
			(effects
				(font
					(size 1.27 1.27)
				)
			)
		)
		(duplicate_pad_numbers_are_jumpers no)
		(fp_line
			(start -0.7874 -0.4064)
			(end 0.7874 -0.4064)
			(stroke
				(width 0.1524)
				(type default)
			)
			(layer "F.SilkS")
		)
		(fp_line
			(start -0.7874 0.4064)
			(end -0.7874 -0.4064)
			(stroke
				(width 0.1524)
				(type default)
			)
			(layer "F.SilkS")
		)
		(fp_line
			(start 0.7874 -0.4064)
			(end 0.7874 0.4064)
			(stroke
				(width 0.1524)
				(type default)
			)
			(layer "F.SilkS")
		)
		(fp_line
			(start 0.7874 0.4064)
			(end -0.7874 0.4064)
			(stroke
				(width 0.1524)
				(type default)
			)
			(layer "F.SilkS")
		)
		(fp_poly
			(pts
				(xy -0.508 0.2794) (xy -0.508 0.2286) (xy -0.635 0.2286) (xy -0.635 -0.254) (xy -0.5334 -0.254)
				(xy -0.5334 -0.2794) (xy 0.5334 -0.2794) (xy 0.5334 -0.254) (xy 0.635 -0.254) (xy 0.635 0.254) (xy 0.5334 0.254)
				(xy 0.5334 0.2794)
			)
			(stroke
				(width 0)
				(type default)
			)
			(fill no)
			(layer "F.CrtYd")
		)
		(pad "1" smd rect
			(at 0.40005 0)
			(size 0.4572 0.508)
			(layers "F.Cu" "F.Mask" "F.Paste")
			(net "P3V3_STB_NODE1")
		)
		(pad "2" smd rect
			(at -0.40005 0)
			(size 0.4572 0.508)
			(layers "F.Cu" "F.Mask" "F.Paste")
			(net "PWRGD_NODE1_P1V0")
		)
	)
	(footprint ""
		(layer "F.Cu")
		(at 174.411894 -130.63982 90)
		(property "Reference" "R1036"
			(at -1.213866 12.029948 90)
			(unlocked yes)
			(layer "F.SilkS")
			(effects
				(font
					(size 0.7874 0.5842)
					(thickness 0.1524)
				)
				(justify left)
			)
		)
		(property "Value" ""
			(at 0 0 90)
			(layer "F.Fab")
			(effects
				(font
					(size 1.27 1.27)
				)
			)
		)
		(duplicate_pad_numbers_are_jumpers no)
		(fp_line
			(start 0.7874 -0.4064)
			(end 0.7874 0.4064)
			(stroke
				(width 0.1524)
				(type default)
			)
			(layer "F.SilkS")
		)
		(fp_line
			(start -0.7874 -0.4064)
			(end 0.7874 -0.4064)
			(stroke
				(width 0.1524)
				(type default)
			)
			(layer "F.SilkS")
		)
		(fp_line
			(start 0.7874 0.4064)
			(end -0.7874 0.4064)
			(stroke
				(width 0.1524)
				(type default)
			)
			(layer "F.SilkS")
		)
		(fp_line
			(start -0.7874 0.4064)
			(end -0.7874 -0.4064)
			(stroke
				(width 0.1524)
				(type default)
			)
			(layer "F.SilkS")
		)
		(fp_poly
			(pts
				(xy -0.508 0.2794) (xy -0.508 0.2286) (xy -0.635 0.2286) (xy -0.635 -0.254) (xy -0.5334 -0.254)
				(xy -0.5334 -0.2794) (xy 0.5334 -0.2794) (xy 0.5334 -0.254) (xy 0.635 -0.254) (xy 0.635 0.254) (xy 0.5334 0.254)
				(xy 0.5334 0.2794)
			)
			(stroke
				(width 0)
				(type default)
			)
			(fill no)
			(layer "F.CrtYd")
		)
		(pad "1" smd rect
			(at 0.40005 0 90)
			(size 0.4572 0.508)
			(layers "F.Cu" "F.Mask" "F.Paste")
			(net "P3V3_STB_NODE1")
		)
		(pad "2" smd rect
			(at -0.40005 0 90)
			(size 0.4572 0.508)
			(layers "F.Cu" "F.Mask" "F.Paste")
			(net "FM_CPLD_NODE1_DEBUG_MODE")
		)
	)
	(footprint ""
		(layer "F.Cu")
		(at 20.413472 -128.92913 -90)
		(property "Reference" "PR23"
			(at 2.648712 -4.882642 90)
			(unlocked yes)
			(layer "F.SilkS")
			(effects
				(font
					(size 0.7874 0.5842)
					(thickness 0.1524)
				)
				(justify left)
			)
		)
		(property "Value" ""
			(at 0 0 270)
			(layer "F.Fab")
			(effects
				(font
					(size 1.27 1.27)
				)
			)
		)
		(duplicate_pad_numbers_are_jumpers no)
		(fp_line
			(start -0.7874 0.4064)
			(end -0.7874 -0.4064)
			(stroke
				(width 0.1524)
				(type default)
			)
			(layer "F.SilkS")
		)
		(fp_line
			(start 0.7874 0.4064)
			(end -0.7874 0.4064)
			(stroke
				(width 0.1524)
				(type default)
			)
			(layer "F.SilkS")
		)
		(fp_line
			(start -0.7874 -0.4064)
			(end 0.7874 -0.4064)
			(stroke
				(width 0.1524)
				(type default)
			)
			(layer "F.SilkS")
		)
		(fp_line
			(start 0.7874 -0.4064)
			(end 0.7874 0.4064)
			(stroke
				(width 0.1524)
				(type default)
			)
			(layer "F.SilkS")
		)
		(fp_poly
			(pts
				(xy -0.508 0.2794) (xy -0.508 0.2286) (xy -0.635 0.2286) (xy -0.635 -0.254) (xy -0.5334 -0.254)
				(xy -0.5334 -0.2794) (xy 0.5334 -0.2794) (xy 0.5334 -0.254) (xy 0.635 -0.254) (xy 0.635 0.254) (xy 0.5334 0.254)
				(xy 0.5334 0.2794)
			)
			(stroke
				(width 0)
				(type default)
			)
			(fill no)
			(layer "F.CrtYd")
		)
		(pad "1" smd rect
			(at 0.40005 0 270)
			(size 0.4572 0.508)
			(layers "F.Cu" "F.Mask" "F.Paste")
			(net "P3V3_NODE1")
		)
		(pad "2" smd rect
			(at -0.40005 0 270)
			(size 0.4572 0.508)
			(layers "F.Cu" "F.Mask" "F.Paste")
			(net "P1V05_NODE1_EN")
		)
	)
)
